(kicad_pcb
	(version 20260206)
	(generator "pcbnew")
	(generator_version "10.0")
	(general
		(thickness 1.6)
		(legacy_teardrops no)
	)
	(paper "A4")
	(title_block
		(title "04192023_DAF0TMB3IC0_F0TG_MB_C_brd_V02_OCP.brd")
		(comment 1 "Grand Teton / footprints 5349-5354 of 8354")
	)
	(layers
		(0 "F.Cu" signal "TOP")
		(4 "In1.Cu" signal "GND")
		(6 "In2.Cu" signal "IN1")
		(8 "In3.Cu" signal "GND1")
		(10 "In4.Cu" signal "IN2")
		(12 "In5.Cu" signal "GND2")
		(14 "In6.Cu" signal "IN3")
		(16 "In7.Cu" signal "GND3")
		(18 "In8.Cu" signal "VCC")
		(20 "In9.Cu" signal "VCC1")
		(22 "In10.Cu" signal "GND4")
		(24 "In11.Cu" signal "IN4")
		(26 "In12.Cu" signal "GND5")
		(28 "In13.Cu" signal "IN5")
		(30 "In14.Cu" signal "GND6")
		(32 "In15.Cu" signal "IN6")
		(34 "In16.Cu" signal "GND7")
		(2 "B.Cu" signal "BOTTOM")
		(9 "F.Adhes" user "F.Adhesive")
		(11 "B.Adhes" user "B.Adhesive")
		(13 "F.Paste" user "Package Geometry/Pastemask Top")
		(15 "B.Paste" user "Package Geometry/Pastemask Bottom")
		(5 "F.SilkS" user "Ref Des/Silkscreen Top")
		(7 "B.SilkS" user "Ref Des/Silkscreen Bottom")
		(1 "F.Mask" user "Board Geometry/Soldermask Top")
		(3 "B.Mask" user "Board Geometry/Soldermask Bottom")
		(17 "Dwgs.User" user "User.Drawings")
		(19 "Cmts.User" user "User.Comments")
		(21 "Eco1.User" user "User.Eco1")
		(23 "Eco2.User" user "User.Eco2")
		(25 "Edge.Cuts" user "Board Geometry/Outline")
		(27 "Margin" user)
		(31 "F.CrtYd" user "Package Geometry/Place Bound Top")
		(29 "B.CrtYd" user "Package Geometry/Place Bound Bottom")
		(35 "F.Fab" user "Ref Des/Assembly Top")
		(33 "B.Fab" user "Ref Des/Assembly Bottom")
	)
	(footprint ""
		(layer "B.Cu")
		(at 367.544858 -142.574772 180)
		(property "Reference" "PR285"
			(at 0 0 0)
			(layer "B.SilkS")
			(hide yes)
			(effects
				(font
					(size 1.27 1.27)
				)
				(justify mirror)
			)
		)
		(property "Value" ""
			(at 0 0 0)
			(layer "B.Fab")
			(effects
				(font
					(size 1.27 1.27)
				)
				(justify mirror)
			)
		)
		(duplicate_pad_numbers_are_jumpers no)
		(fp_line
			(start 0.7874 0.4064)
			(end 0.7874 -0.4064)
			(stroke
				(width 0.1524)
				(type default)
			)
			(layer "B.SilkS")
		)
		(fp_line
			(start 0.7874 -0.4064)
			(end -0.7874 -0.4064)
			(stroke
				(width 0.1524)
				(type default)
			)
			(layer "B.SilkS")
		)
		(fp_line
			(start -0.7874 0.4064)
			(end 0.7874 0.4064)
			(stroke
				(width 0.1524)
				(type default)
			)
			(layer "B.SilkS")
		)
		(fp_line
			(start -0.7874 -0.4064)
			(end -0.7874 0.4064)
			(stroke
				(width 0.1524)
				(type default)
			)
			(layer "B.SilkS")
		)
		(fp_line
			(start 0.67945 0.3048)
			(end 0.67945 -0.305054)
			(stroke
				(width 0.1)
				(type default)
			)
			(layer "B.Fab")
		)
		(fp_line
			(start 0.67945 -0.305054)
			(end 0.12065 -0.305054)
			(stroke
				(width 0.1)
				(type default)
			)
			(layer "B.Fab")
		)
		(fp_line
			(start 0.12065 0.3048)
			(end 0.67945 0.3048)
			(stroke
				(width 0.1)
				(type default)
			)
			(layer "B.Fab")
		)
		(fp_line
			(start 0.12065 0.2794)
			(end 0.12065 0.3048)
			(stroke
				(width 0.1)
				(type default)
			)
			(layer "B.Fab")
		)
		(fp_line
			(start 0.12065 -0.2794)
			(end -0.12065 -0.2794)
			(stroke
				(width 0.1)
				(type default)
			)
			(layer "B.Fab")
		)
		(fp_line
			(start 0.12065 -0.305054)
			(end 0.12065 -0.2794)
			(stroke
				(width 0.1)
				(type default)
			)
			(layer "B.Fab")
		)
		(fp_line
			(start -0.120396 0.3048)
			(end -0.120396 0.2794)
			(stroke
				(width 0.1)
				(type default)
			)
			(layer "B.Fab")
		)
		(fp_line
			(start -0.120396 0.2794)
			(end 0.12065 0.2794)
			(stroke
				(width 0.1)
				(type default)
			)
			(layer "B.Fab")
		)
		(fp_line
			(start -0.12065 -0.2794)
			(end -0.12065 -0.3048)
			(stroke
				(width 0.1)
				(type default)
			)
			(layer "B.Fab")
		)
		(fp_line
			(start -0.12065 -0.3048)
			(end -0.67945 -0.3048)
			(stroke
				(width 0.1)
				(type default)
			)
			(layer "B.Fab")
		)
		(fp_line
			(start -0.67945 0.3048)
			(end -0.120396 0.3048)
			(stroke
				(width 0.1)
				(type default)
			)
			(layer "B.Fab")
		)
		(fp_line
			(start -0.67945 -0.3048)
			(end -0.67945 0.3048)
			(stroke
				(width 0.1)
				(type default)
			)
			(layer "B.Fab")
		)
		(pad "1" smd circle
			(at 0.40005 0)
			(size 0 0)
			(layers "B.Cu" "B.Mask" "B.Paste")
			(net "P3V3_AUX")
		)
		(pad "2" smd circle
			(at -0.40005 0)
			(size 0 0)
			(layers "B.Cu" "B.Mask" "B.Paste")
			(net "PVDDCR_SOC_P0_EN_GD")
		)
	)
	(footprint ""
		(layer "B.Cu")
		(at 228.420422 -329.698858 180)
		(property "Reference" "C1090"
			(at 0 0 0)
			(layer "B.SilkS")
			(hide yes)
			(effects
				(font
					(size 1.27 1.27)
				)
				(justify mirror)
			)
		)
		(property "Value" ""
			(at 0 0 0)
			(layer "B.Fab")
			(effects
				(font
					(size 1.27 1.27)
				)
				(justify mirror)
			)
		)
		(duplicate_pad_numbers_are_jumpers no)
		(fp_line
			(start 0.7874 0.4064)
			(end 0.7874 -0.4064)
			(stroke
				(width 0.1524)
				(type default)
			)
			(layer "B.SilkS")
		)
		(fp_line
			(start 0.7874 -0.4064)
			(end -0.7874 -0.4064)
			(stroke
				(width 0.1524)
				(type default)
			)
			(layer "B.SilkS")
		)
		(fp_line
			(start -0.7874 0.4064)
			(end 0.7874 0.4064)
			(stroke
				(width 0.1524)
				(type default)
			)
			(layer "B.SilkS")
		)
		(fp_line
			(start -0.7874 -0.4064)
			(end -0.7874 0.4064)
			(stroke
				(width 0.1524)
				(type default)
			)
			(layer "B.SilkS")
		)
		(fp_line
			(start 0.67945 0.3048)
			(end 0.67945 -0.305054)
			(stroke
				(width 0.1)
				(type default)
			)
			(layer "B.Fab")
		)
		(fp_line
			(start 0.67945 -0.305054)
			(end 0.12065 -0.305054)
			(stroke
				(width 0.1)
				(type default)
			)
			(layer "B.Fab")
		)
		(fp_line
			(start 0.12065 0.3048)
			(end 0.67945 0.3048)
			(stroke
				(width 0.1)
				(type default)
			)
			(layer "B.Fab")
		)
		(fp_line
			(start 0.12065 0.2794)
			(end 0.12065 0.3048)
			(stroke
				(width 0.1)
				(type default)
			)
			(layer "B.Fab")
		)
		(fp_line
			(start 0.12065 -0.2794)
			(end -0.12065 -0.2794)
			(stroke
				(width 0.1)
				(type default)
			)
			(layer "B.Fab")
		)
		(fp_line
			(start 0.12065 -0.305054)
			(end 0.12065 -0.2794)
			(stroke
				(width 0.1)
				(type default)
			)
			(layer "B.Fab")
		)
		(fp_line
			(start -0.120396 0.3048)
			(end -0.120396 0.2794)
			(stroke
				(width 0.1)
				(type default)
			)
			(layer "B.Fab")
		)
		(fp_line
			(start -0.120396 0.2794)
			(end 0.12065 0.2794)
			(stroke
				(width 0.1)
				(type default)
			)
			(layer "B.Fab")
		)
		(fp_line
			(start -0.12065 -0.2794)
			(end -0.12065 -0.3048)
			(stroke
				(width 0.1)
				(type default)
			)
			(layer "B.Fab")
		)
		(fp_line
			(start -0.12065 -0.3048)
			(end -0.67945 -0.3048)
			(stroke
				(width 0.1)
				(type default)
			)
			(layer "B.Fab")
		)
		(fp_line
			(start -0.67945 0.3048)
			(end -0.120396 0.3048)
			(stroke
				(width 0.1)
				(type default)
			)
			(layer "B.Fab")
		)
		(fp_line
			(start -0.67945 -0.3048)
			(end -0.67945 0.3048)
			(stroke
				(width 0.1)
				(type default)
			)
			(layer "B.Fab")
		)
		(pad "1" smd circle
			(at 0.40005 0)
			(size 0 0)
			(layers "B.Cu" "B.Mask" "B.Paste")
			(net "PVDD18_S5_P1_ADC_TIC")
		)
		(pad "2" smd circle
			(at -0.40005 0)
			(size 0 0)
			(layers "B.Cu" "B.Mask" "B.Paste")
			(net "GND")
		)
	)
	(footprint ""
		(layer "B.Cu")
		(at 102.783386 -266.005564)
		(property "Reference" "C2115"
			(at 0 0 0)
			(layer "B.SilkS")
			(hide yes)
			(effects
				(font
					(size 1.27 1.27)
				)
				(justify mirror)
			)
		)
		(property "Value" ""
			(at 0 0 0)
			(layer "B.Fab")
			(effects
				(font
					(size 1.27 1.27)
				)
				(justify mirror)
			)
		)
		(duplicate_pad_numbers_are_jumpers no)
		(fp_line
			(start -0.7874 -0.4064)
			(end -0.7874 0.4064)
			(stroke
				(width 0.1524)
				(type default)
			)
			(layer "B.SilkS")
		)
		(fp_line
			(start -0.7874 0.4064)
			(end 0.7874 0.4064)
			(stroke
				(width 0.1524)
				(type default)
			)
			(layer "B.SilkS")
		)
		(fp_line
			(start 0.7874 -0.4064)
			(end -0.7874 -0.4064)
			(stroke
				(width 0.1524)
				(type default)
			)
			(layer "B.SilkS")
		)
		(fp_line
			(start 0.7874 0.4064)
			(end 0.7874 -0.4064)
			(stroke
				(width 0.1524)
				(type default)
			)
			(layer "B.SilkS")
		)
		(fp_line
			(start -0.67945 -0.3048)
			(end -0.67945 0.3048)
			(stroke
				(width 0.1)
				(type default)
			)
			(layer "B.Fab")
		)
		(fp_line
			(start -0.67945 0.3048)
			(end -0.120396 0.3048)
			(stroke
				(width 0.1)
				(type default)
			)
			(layer "B.Fab")
		)
		(fp_line
			(start -0.12065 -0.3048)
			(end -0.67945 -0.3048)
			(stroke
				(width 0.1)
				(type default)
			)
			(layer "B.Fab")
		)
		(fp_line
			(start -0.12065 -0.2794)
			(end -0.12065 -0.3048)
			(stroke
				(width 0.1)
				(type default)
			)
			(layer "B.Fab")
		)
		(fp_line
			(start -0.120396 0.2794)
			(end 0.12065 0.2794)
			(stroke
				(width 0.1)
				(type default)
			)
			(layer "B.Fab")
		)
		(fp_line
			(start -0.120396 0.3048)
			(end -0.120396 0.2794)
			(stroke
				(width 0.1)
				(type default)
			)
			(layer "B.Fab")
		)
		(fp_line
			(start 0.12065 -0.305054)
			(end 0.12065 -0.2794)
			(stroke
				(width 0.1)
				(type default)
			)
			(layer "B.Fab")
		)
		(fp_line
			(start 0.12065 -0.2794)
			(end -0.12065 -0.2794)
			(stroke
				(width 0.1)
				(type default)
			)
			(layer "B.Fab")
		)
		(fp_line
			(start 0.12065 0.2794)
			(end 0.12065 0.3048)
			(stroke
				(width 0.1)
				(type default)
			)
			(layer "B.Fab")
		)
		(fp_line
			(start 0.12065 0.3048)
			(end 0.67945 0.3048)
			(stroke
				(width 0.1)
				(type default)
			)
			(layer "B.Fab")
		)
		(fp_line
			(start 0.67945 -0.305054)
			(end 0.12065 -0.305054)
			(stroke
				(width 0.1)
				(type default)
			)
			(layer "B.Fab")
		)
		(fp_line
			(start 0.67945 0.3048)
			(end 0.67945 -0.305054)
			(stroke
				(width 0.1)
				(type default)
			)
			(layer "B.Fab")
		)
		(pad "1" smd circle
			(at 0.40005 0 180)
			(size 0 0)
			(layers "B.Cu" "B.Mask" "B.Paste")
			(net "PVDD11_S3_P1")
		)
		(pad "2" smd circle
			(at -0.40005 0 180)
			(size 0 0)
			(layers "B.Cu" "B.Mask" "B.Paste")
			(net "GND")
		)
	)
	(footprint ""
		(layer "B.Cu")
		(at 131.29133 -390.560052 90)
		(property "Reference" "C494"
			(at 0 0 90)
			(layer "B.SilkS")
			(hide yes)
			(effects
				(font
					(size 1.27 1.27)
				)
				(justify mirror)
			)
		)
		(property "Value" ""
			(at 0 0 90)
			(layer "B.Fab")
			(effects
				(font
					(size 1.27 1.27)
				)
				(justify mirror)
			)
		)
		(duplicate_pad_numbers_are_jumpers no)
		(fp_line
			(start 0.7874 -0.4064)
			(end -0.7874 -0.4064)
			(stroke
				(width 0.1524)
				(type default)
			)
			(layer "B.SilkS")
		)
		(fp_line
			(start -0.7874 -0.4064)
			(end -0.7874 0.4064)
			(stroke
				(width 0.1524)
				(type default)
			)
			(layer "B.SilkS")
		)
		(fp_line
			(start 0.7874 0.4064)
			(end 0.7874 -0.4064)
			(stroke
				(width 0.1524)
				(type default)
			)
			(layer "B.SilkS")
		)
		(fp_line
			(start -0.7874 0.4064)
			(end 0.7874 0.4064)
			(stroke
				(width 0.1524)
				(type default)
			)
			(layer "B.SilkS")
		)
		(fp_line
			(start 0.67945 -0.305054)
			(end 0.12065 -0.305054)
			(stroke
				(width 0.1)
				(type default)
			)
			(layer "B.Fab")
		)
		(fp_line
			(start 0.12065 -0.305054)
			(end 0.12065 -0.2794)
			(stroke
				(width 0.1)
				(type default)
			)
			(layer "B.Fab")
		)
		(fp_line
			(start -0.12065 -0.3048)
			(end -0.67945 -0.3048)
			(stroke
				(width 0.1)
				(type default)
			)
			(layer "B.Fab")
		)
		(fp_line
			(start -0.67945 -0.3048)
			(end -0.67945 0.3048)
			(stroke
				(width 0.1)
				(type default)
			)
			(layer "B.Fab")
		)
		(fp_line
			(start 0.12065 -0.2794)
			(end -0.12065 -0.2794)
			(stroke
				(width 0.1)
				(type default)
			)
			(layer "B.Fab")
		)
		(fp_line
			(start -0.12065 -0.2794)
			(end -0.12065 -0.3048)
			(stroke
				(width 0.1)
				(type default)
			)
			(layer "B.Fab")
		)
		(fp_line
			(start 0.12065 0.2794)
			(end 0.12065 0.3048)
			(stroke
				(width 0.1)
				(type default)
			)
			(layer "B.Fab")
		)
		(fp_line
			(start -0.120396 0.2794)
			(end 0.12065 0.2794)
			(stroke
				(width 0.1)
				(type default)
			)
			(layer "B.Fab")
		)
		(fp_line
			(start 0.67945 0.3048)
			(end 0.67945 -0.305054)
			(stroke
				(width 0.1)
				(type default)
			)
			(layer "B.Fab")
		)
		(fp_line
			(start 0.12065 0.3048)
			(end 0.67945 0.3048)
			(stroke
				(width 0.1)
				(type default)
			)
			(layer "B.Fab")
		)
		(fp_line
			(start -0.120396 0.3048)
			(end -0.120396 0.2794)
			(stroke
				(width 0.1)
				(type default)
			)
			(layer "B.Fab")
		)
		(fp_line
			(start -0.67945 0.3048)
			(end -0.120396 0.3048)
			(stroke
				(width 0.1)
				(type default)
			)
			(layer "B.Fab")
		)
		(pad "1" smd circle
			(at 0.40005 0 270)
			(size 0 0)
			(layers "B.Cu" "B.Mask" "B.Paste")
			(net "P0V9_CPU1_RT3_2A")
		)
		(pad "2" smd circle
			(at -0.40005 0 270)
			(size 0 0)
			(layers "B.Cu" "B.Mask" "B.Paste")
			(net "GND")
		)
	)
	(footprint ""
		(layer "B.Cu")
		(at 391.636758 -202.48499)
		(property "Reference" "R6083"
			(at 0 0 0)
			(layer "B.SilkS")
			(hide yes)
			(effects
				(font
					(size 1.27 1.27)
				)
				(justify mirror)
			)
		)
		(property "Value" ""
			(at 0 0 0)
			(layer "B.Fab")
			(effects
				(font
					(size 1.27 1.27)
				)
				(justify mirror)
			)
		)
		(duplicate_pad_numbers_are_jumpers no)
		(fp_line
			(start -0.7874 -0.4064)
			(end -0.7874 0.4064)
			(stroke
				(width 0.1524)
				(type default)
			)
			(layer "B.SilkS")
		)
		(fp_line
			(start -0.7874 0.4064)
			(end 0.7874 0.4064)
			(stroke
				(width 0.1524)
				(type default)
			)
			(layer "B.SilkS")
		)
		(fp_line
			(start 0.7874 -0.4064)
			(end -0.7874 -0.4064)
			(stroke
				(width 0.1524)
				(type default)
			)
			(layer "B.SilkS")
		)
		(fp_line
			(start 0.7874 0.4064)
			(end 0.7874 -0.4064)
			(stroke
				(width 0.1524)
				(type default)
			)
			(layer "B.SilkS")
		)
		(fp_line
			(start -0.67945 -0.3048)
			(end -0.67945 0.3048)
			(stroke
				(width 0.1)
				(type default)
			)
			(layer "B.Fab")
		)
		(fp_line
			(start -0.67945 0.3048)
			(end -0.120396 0.3048)
			(stroke
				(width 0.1)
				(type default)
			)
			(layer "B.Fab")
		)
		(fp_line
			(start -0.12065 -0.3048)
			(end -0.67945 -0.3048)
			(stroke
				(width 0.1)
				(type default)
			)
			(layer "B.Fab")
		)
		(fp_line
			(start -0.12065 -0.2794)
			(end -0.12065 -0.3048)
			(stroke
				(width 0.1)
				(type default)
			)
			(layer "B.Fab")
		)
		(fp_line
			(start -0.120396 0.2794)
			(end 0.12065 0.2794)
			(stroke
				(width 0.1)
				(type default)
			)
			(layer "B.Fab")
		)
		(fp_line
			(start -0.120396 0.3048)
			(end -0.120396 0.2794)
			(stroke
				(width 0.1)
				(type default)
			)
			(layer "B.Fab")
		)
		(fp_line
			(start 0.12065 -0.305054)
			(end 0.12065 -0.2794)
			(stroke
				(width 0.1)
				(type default)
			)
			(layer "B.Fab")
		)
		(fp_line
			(start 0.12065 -0.2794)
			(end -0.12065 -0.2794)
			(stroke
				(width 0.1)
				(type default)
			)
			(layer "B.Fab")
		)
		(fp_line
			(start 0.12065 0.2794)
			(end 0.12065 0.3048)
			(stroke
				(width 0.1)
				(type default)
			)
			(layer "B.Fab")
		)
		(fp_line
			(start 0.12065 0.3048)
			(end 0.67945 0.3048)
			(stroke
				(width 0.1)
				(type default)
			)
			(layer "B.Fab")
		)
		(fp_line
			(start 0.67945 -0.305054)
			(end 0.12065 -0.305054)
			(stroke
				(width 0.1)
				(type default)
			)
			(layer "B.Fab")
		)
		(fp_line
			(start 0.67945 0.3048)
			(end 0.67945 -0.305054)
			(stroke
				(width 0.1)
				(type default)
			)
			(layer "B.Fab")
		)
		(pad "1" smd circle
			(at 0.40005 0 180)
			(size 0 0)
			(layers "B.Cu" "B.Mask" "B.Paste")
			(net "PVDD11_S3_P0")
		)
		(pad "2" smd circle
			(at -0.40005 0 180)
			(size 0 0)
			(layers "B.Cu" "B.Mask" "B.Paste")
			(net "SMB_CPU0_3_SCL")
		)
	)
	(footprint ""
		(layer "B.Cu")
		(at 18.841974 -373.339614 90)
		(property "Reference" "PC6627"
			(at -3.642614 -2.993644 270)
			(unlocked yes)
			(layer "B.SilkS")
			(effects
				(font
					(size 0.7874 0.5842)
					(thickness 0.1524)
				)
				(justify left mirror)
			)
		)
		(property "Value" ""
			(at 0 0 90)
			(layer "B.Fab")
			(effects
				(font
					(size 1.27 1.27)
				)
				(justify mirror)
			)
		)
		(duplicate_pad_numbers_are_jumpers no)
		(fp_line
			(start 4.84378 -2.150618)
			(end 4.53898 -2.150618)
			(stroke
				(width 0.1524)
				(type default)
			)
			(layer "B.SilkS")
		)
		(fp_line
			(start 4.84378 -2.150618)
			(end 4.842256 2.163064)
			(stroke
				(width 0.1524)
				(type default)
			)
			(layer "B.SilkS")
		)
		(fp_line
			(start 4.69138 -2.150618)
			(end 4.692396 2.161032)
			(stroke
				(width 0.1524)
				(type default)
			)
			(layer "B.SilkS")
		)
		(fp_line
			(start 4.53898 -2.150618)
			(end 4.539742 2.152142)
			(stroke
				(width 0.1524)
				(type default)
			)
			(layer "B.SilkS")
		)
		(fp_line
			(start 4.53898 -2.15011)
			(end -4.53898 -2.15011)
			(stroke
				(width 0.1524)
				(type default)
			)
			(layer "B.SilkS")
		)
		(fp_line
			(start -4.53898 -2.15011)
			(end -4.53898 2.15011)
			(stroke
				(width 0.1524)
				(type default)
			)
			(layer "B.SilkS")
		)
		(fp_line
			(start 4.53898 2.15011)
			(end 4.53898 -2.15011)
			(stroke
				(width 0.1524)
				(type default)
			)
			(layer "B.SilkS")
		)
		(fp_line
			(start -4.53898 2.15011)
			(end 4.53898 2.15011)
			(stroke
				(width 0.1524)
				(type default)
			)
			(layer "B.SilkS")
		)
		(fp_line
			(start 4.83108 2.150364)
			(end 4.447794 2.149348)
			(stroke
				(width 0.1524)
				(type default)
			)
			(layer "B.SilkS")
		)
		(fp_line
			(start 3.64998 -2.15011)
			(end -3.64998 -2.15011)
			(stroke
				(width 0.1)
				(type default)
			)
			(layer "B.Fab")
		)
		(fp_line
			(start -3.64998 -2.15011)
			(end -3.64998 2.15011)
			(stroke
				(width 0.1)
				(type default)
			)
			(layer "B.Fab")
		)
		(fp_line
			(start 3.64998 2.15011)
			(end 3.64998 -2.15011)
			(stroke
				(width 0.1)
				(type default)
			)
			(layer "B.Fab")
		)
		(fp_line
			(start -3.64998 2.15011)
			(end 3.64998 2.15011)
			(stroke
				(width 0.1)
				(type default)
			)
			(layer "B.Fab")
		)
		(fp_text user "+"
			(at 6.338824 -1.180084 90)
			(unlocked yes)
			(layer "B.SilkS")
			(effects
				(font
					(size 1.905 1.4224)
					(thickness 0.1524)
				)
				(justify left mirror)
			)
		)
		(fp_text user "-"
			(at -4.313174 -0.094488 90)
			(unlocked yes)
			(layer "B.SilkS")
			(effects
				(font
					(size 1.905 1.4224)
					(thickness 0.1524)
				)
				(justify left mirror)
			)
		)
		(fp_text user "+"
			(at 6.214872 -0.337058 90)
			(unlocked yes)
			(layer "B.Fab")
			(effects
				(font
					(size 1.905 1.4224)
					(thickness 0.1524)
				)
				(justify left mirror)
			)
		)
		(fp_text user "-"
			(at -4.313174 -0.094488 90)
			(unlocked yes)
			(layer "B.Fab")
			(effects
				(font
					(size 1.905 1.4224)
					(thickness 0.1524)
				)
				(justify left mirror)
			)
		)
		(pad "1" smd rect
			(at 3.199892 0 270)
			(size 2.413 2.8194)
			(layers "B.Cu" "B.Mask" "B.Paste")
			(net "P0V9_CPU1_RT_2D")
		)
		(pad "2" smd rect
			(at -3.199892 0 270)
			(size 2.413 2.8194)
			(layers "B.Cu" "B.Mask" "B.Paste")
			(net "GND")
		)
	)
)
